(kicad_pcb
	(version 20260206)
	(generator "pcbnew")
	(generator_version "10.0")
	(general
		(thickness 1.6)
		(legacy_teardrops no)
	)
	(paper "A4")
	(title_block
		(title "Wiwynn_Tioga_Pass_MB.brd")
		(comment 1 "Tioga Pass / footprints 3477-3484 of 4770")
	)
	(layers
		(0 "F.Cu" signal "TOP")
		(4 "In1.Cu" signal "L2GND")
		(6 "In2.Cu" signal "L3")
		(8 "In3.Cu" signal "L4GND")
		(10 "In4.Cu" signal "L5")
		(12 "In5.Cu" signal "L6GND")
		(14 "In6.Cu" signal "L7VCC")
		(16 "In7.Cu" signal "L8VCC")
		(18 "In8.Cu" signal "L9GND")
		(20 "In9.Cu" signal "L10")
		(22 "In10.Cu" signal "L11GND")
		(24 "In11.Cu" signal "L12")
		(26 "In12.Cu" signal "L13GND")
		(2 "B.Cu" signal "BOTTOM")
		(9 "F.Adhes" user "F.Adhesive")
		(11 "B.Adhes" user "B.Adhesive")
		(13 "F.Paste" user "Package Geometry/Pastemask Top")
		(15 "B.Paste" user "Package Geometry/Pastemask Bottom")
		(5 "F.SilkS" user "Ref Des/Silkscreen Top")
		(7 "B.SilkS" user "Ref Des/Silkscreen Bottom")
		(1 "F.Mask" user "Board Geometry/Soldermask Top")
		(3 "B.Mask" user "Board Geometry/Soldermask Bottom")
		(17 "Dwgs.User" user "User.Drawings")
		(19 "Cmts.User" user "User.Comments")
		(21 "Eco1.User" user "User.Eco1")
		(23 "Eco2.User" user "User.Eco2")
		(25 "Edge.Cuts" user "Board Geometry/Outline")
		(27 "Margin" user)
		(31 "F.CrtYd" user "Package Geometry/Place Bound Top")
		(29 "B.CrtYd" user "Package Geometry/Place Bound Bottom")
		(35 "F.Fab" user "Ref Des/Assembly Top")
		(33 "B.Fab" user "Ref Des/Assembly Bottom")
	)
	(footprint ""
		(layer "B.Cu")
		(at 367.157 -40.5892 180)
		(property "Reference" "R8F14"
			(at 0 0 0)
			(layer "B.SilkS")
			(hide yes)
			(effects
				(font
					(size 1.27 1.27)
				)
				(justify mirror)
			)
		)
		(property "Value" ""
			(at 0 0 0)
			(layer "B.Fab")
			(effects
				(font
					(size 1.27 1.27)
				)
				(justify mirror)
			)
		)
		(duplicate_pad_numbers_are_jumpers no)
		(fp_poly
			(pts
				(xy 0.2794 -0.1016) (xy -0.2794 -0.1016) (xy -0.2794 0.9906) (xy 0.2794 0.9906)
			)
			(stroke
				(width 0)
				(type default)
			)
			(fill no)
			(layer "B.CrtYd")
		)
		(fp_line
			(start 0.2794 0.9906)
			(end -0.2794 0.9906)
			(stroke
				(width 0.1)
				(type default)
			)
			(layer "B.Fab")
		)
		(fp_line
			(start 0.2794 -0.1016)
			(end 0.2794 0.9906)
			(stroke
				(width 0.1)
				(type default)
			)
			(layer "B.Fab")
		)
		(fp_line
			(start -0.2794 0.9906)
			(end -0.2794 -0.1016)
			(stroke
				(width 0.1)
				(type default)
			)
			(layer "B.Fab")
		)
		(fp_line
			(start -0.2794 -0.1016)
			(end 0.2794 -0.1016)
			(stroke
				(width 0.1)
				(type default)
			)
			(layer "B.Fab")
		)
		(pad "1" smd rect
			(at 0 0)
			(size 0.508 0.508)
			(layers "B.Cu" "B.Mask" "B.Paste")
			(net "P3V3_STBY")
		)
		(pad "2" smd rect
			(at 0 0.889)
			(size 0.508 0.508)
			(layers "B.Cu" "B.Mask" "B.Paste")
			(net "PU_SPI_BMC_BT_HOLD_N")
		)
		(zone
			(layer "B.Cu")
			(hatch none 0.5)
			(connect_pads
				(clearance 0)
			)
			(min_thickness 0.25)
			(keepout
				(tracks not_allowed)
				(vias allowed)
				(pads allowed)
				(copperpour not_allowed)
				(footprints allowed)
			)
			(placement
				(enabled no)
				(sheetname "")
			)
			(fill
				(thermal_gap 0.5)
				(thermal_bridge_width 0.5)
				(island_removal_mode 0)
			)
			(polygon
				(pts
					(xy 366.903 -41.2242) (xy 367.411 -41.2242) (xy 367.411 -40.8432) (xy 366.903 -40.8432)
				)
			)
		)
		(zone
			(layer "B.Cu")
			(hatch none 0.5)
			(connect_pads
				(clearance 0)
			)
			(min_thickness 0.25)
			(keepout
				(tracks allowed)
				(vias not_allowed)
				(pads allowed)
				(copperpour not_allowed)
				(footprints allowed)
			)
			(placement
				(enabled no)
				(sheetname "")
			)
			(fill
				(thermal_gap 0.5)
				(thermal_bridge_width 0.5)
				(island_removal_mode 0)
			)
			(polygon
				(pts
					(xy 366.903 -40.8432) (xy 367.411 -40.8432) (xy 367.411 -41.2242) (xy 366.903 -41.2242)
				)
			)
		)
	)
	(footprint ""
		(layer "B.Cu")
		(at 463.492088 -11.993372 -90)
		(property "Reference" "C2U1"
			(at 0 0 90)
			(layer "B.SilkS")
			(hide yes)
			(effects
				(font
					(size 1.27 1.27)
				)
				(justify mirror)
			)
		)
		(property "Value" ""
			(at 0 0 90)
			(layer "B.Fab")
			(effects
				(font
					(size 1.27 1.27)
				)
				(justify mirror)
			)
		)
		(duplicate_pad_numbers_are_jumpers no)
		(fp_rect
			(start -0.7239 1.9939)
			(end 0.7239 -0.2159)
			(stroke
				(width 0)
				(type default)
			)
			(fill no)
			(layer "B.CrtYd")
		)
		(fp_line
			(start -0.7239 1.9939)
			(end -0.7239 -0.2159)
			(stroke
				(width 0.1)
				(type default)
			)
			(layer "B.Fab")
		)
		(fp_line
			(start 0.7239 1.9939)
			(end -0.7239 1.9939)
			(stroke
				(width 0.1)
				(type default)
			)
			(layer "B.Fab")
		)
		(fp_line
			(start -0.7239 -0.2159)
			(end 0.7239 -0.2159)
			(stroke
				(width 0.1)
				(type default)
			)
			(layer "B.Fab")
		)
		(fp_line
			(start 0.7239 -0.2159)
			(end 0.7239 1.9939)
			(stroke
				(width 0.1)
				(type default)
			)
			(layer "B.Fab")
		)
		(pad "1" smd rect
			(at 0 0 90)
			(size 1.27 1.016)
			(layers "B.Cu" "B.Mask" "B.Paste")
			(net "P3V3_STBY")
		)
		(pad "2" smd rect
			(at 0 1.778 90)
			(size 1.27 1.016)
			(layers "B.Cu" "B.Mask" "B.Paste")
			(net "GND")
		)
		(zone
			(layer "B.Cu")
			(hatch none 0.5)
			(connect_pads
				(clearance 0)
			)
			(min_thickness 0.25)
			(keepout
				(tracks not_allowed)
				(vias allowed)
				(pads allowed)
				(copperpour not_allowed)
				(footprints allowed)
			)
			(placement
				(enabled no)
				(sheetname "")
			)
			(fill
				(thermal_gap 0.5)
				(thermal_bridge_width 0.5)
				(island_removal_mode 0)
			)
			(polygon
				(pts
					(xy 462.222088 -12.628372) (xy 462.222088 -11.358372) (xy 462.984088 -11.358372) (xy 462.984088 -12.628372)
				)
			)
		)
	)
	(footprint ""
		(layer "B.Cu")
		(at 485.049322 4.971288 90)
		(property "Reference" "R9G4"
			(at 0 0 90)
			(layer "B.SilkS")
			(hide yes)
			(effects
				(font
					(size 1.27 1.27)
				)
				(justify mirror)
			)
		)
		(property "Value" ""
			(at 0 0 90)
			(layer "B.Fab")
			(effects
				(font
					(size 1.27 1.27)
				)
				(justify mirror)
			)
		)
		(duplicate_pad_numbers_are_jumpers no)
		(fp_poly
			(pts
				(xy 0.2794 -0.1016) (xy -0.2794 -0.1016) (xy -0.2794 0.9906) (xy 0.2794 0.9906)
			)
			(stroke
				(width 0)
				(type default)
			)
			(fill no)
			(layer "B.CrtYd")
		)
		(fp_line
			(start 0.2794 -0.1016)
			(end 0.2794 0.9906)
			(stroke
				(width 0.1)
				(type default)
			)
			(layer "B.Fab")
		)
		(fp_line
			(start -0.2794 -0.1016)
			(end 0.2794 -0.1016)
			(stroke
				(width 0.1)
				(type default)
			)
			(layer "B.Fab")
		)
		(fp_line
			(start 0.2794 0.9906)
			(end -0.2794 0.9906)
			(stroke
				(width 0.1)
				(type default)
			)
			(layer "B.Fab")
		)
		(fp_line
			(start -0.2794 0.9906)
			(end -0.2794 -0.1016)
			(stroke
				(width 0.1)
				(type default)
			)
			(layer "B.Fab")
		)
		(pad "1" smd rect
			(at 0 0 270)
			(size 0.508 0.508)
			(layers "B.Cu" "B.Mask" "B.Paste")
			(net "NIC_LED_ACT_ANODE_R")
		)
		(pad "2" smd rect
			(at 0 0.889 270)
			(size 0.508 0.508)
			(layers "B.Cu" "B.Mask" "B.Paste")
			(net "P3V3_STBY")
		)
		(zone
			(layer "B.Cu")
			(hatch none 0.5)
			(connect_pads
				(clearance 0)
			)
			(min_thickness 0.25)
			(keepout
				(tracks allowed)
				(vias not_allowed)
				(pads allowed)
				(copperpour not_allowed)
				(footprints allowed)
			)
			(placement
				(enabled no)
				(sheetname "")
			)
			(fill
				(thermal_gap 0.5)
				(thermal_bridge_width 0.5)
				(island_removal_mode 0)
			)
			(polygon
				(pts
					(xy 485.303322 4.717288) (xy 485.303322 5.225288) (xy 485.684322 5.225288) (xy 485.684322 4.717288)
				)
			)
		)
		(zone
			(layer "B.Cu")
			(hatch none 0.5)
			(connect_pads
				(clearance 0)
			)
			(min_thickness 0.25)
			(keepout
				(tracks not_allowed)
				(vias allowed)
				(pads allowed)
				(copperpour not_allowed)
				(footprints allowed)
			)
			(placement
				(enabled no)
				(sheetname "")
			)
			(fill
				(thermal_gap 0.5)
				(thermal_bridge_width 0.5)
				(island_removal_mode 0)
			)
			(polygon
				(pts
					(xy 485.684322 4.717288) (xy 485.684322 5.225288) (xy 485.303322 5.225288) (xy 485.303322 4.717288)
				)
			)
		)
	)
	(footprint ""
		(layer "B.Cu")
		(at 439.976006 -43.54195 180)
		(property "Reference" "R25W41"
			(at 0 0 0)
			(layer "B.SilkS")
			(hide yes)
			(effects
				(font
					(size 1.27 1.27)
				)
				(justify mirror)
			)
		)
		(property "Value" "*"
			(at -0.064008 -4.108196 180)
			(unlocked yes)
			(layer "B.Fab")
			(hide yes)
			(effects
				(font
					(size 1.27 1.016)
					(thickness 0.1524)
				)
				(justify mirror)
			)
		)
		(property "Device Type" "120R2F-GP_RCL_GP-120R2F-GP,64.A"
			(at -0.064008 -5.632196 180)
			(unlocked yes)
			(layer "B.Fab")
			(hide yes)
			(effects
				(font
					(size 1.27 1.016)
					(thickness 0.1524)
				)
				(justify mirror)
			)
		)
		(duplicate_pad_numbers_are_jumpers no)
		(fp_line
			(start 0.508 -0.9398)
			(end 0.508 0.9398)
			(stroke
				(width 0.1524)
				(type default)
			)
			(layer "B.SilkS")
		)
		(fp_line
			(start -0.508 -0.9398)
			(end 0.508 -0.9398)
			(stroke
				(width 0.1524)
				(type default)
			)
			(layer "B.SilkS")
		)
		(fp_rect
			(start 0.508 0.9398)
			(end -0.508 -0.9398)
			(stroke
				(width 0)
				(type default)
			)
			(fill no)
			(layer "B.CrtYd")
		)
		(fp_rect
			(start 0.508 0.9398)
			(end -0.508 -0.9398)
			(stroke
				(width 0)
				(type default)
			)
			(fill no)
			(layer "B.Fab")
		)
		(pad "1" smd custom
			(at 0 -0.4445)
			(size 0.1397 0.1397)
			(layers "B.Cu" "B.Mask" "B.Paste")
			(net "BMC_M_A3")
			(options
				(clearance outline)
				(anchor circle)
			)
			(primitives
				(gr_poly
					(pts
						(arc
							(start -0.1778 0.2794)
							(mid -0.249642 0.249642)
							(end -0.2794 0.1778)
						)
						(arc
							(start -0.2794 -0.1778)
							(mid -0.249642 -0.249642)
							(end -0.1778 -0.2794)
						)
						(arc
							(start 0.1778 -0.2794)
							(mid 0.249642 -0.249642)
							(end 0.2794 -0.1778)
						)
						(arc
							(start 0.2794 0.1778)
							(mid 0.249642 0.249642)
							(end 0.1778 0.2794)
						)
					)
					(width 0)
					(fill yes)
				)
			)
		)
		(pad "2" smd custom
			(at 0 0.4445)
			(size 0.1397 0.1397)
			(layers "B.Cu" "B.Mask" "B.Paste")
			(net "P1V2_AUX_BMC")
			(options
				(clearance outline)
				(anchor circle)
			)
			(primitives
				(gr_poly
					(pts
						(arc
							(start -0.1778 0.2794)
							(mid -0.249642 0.249642)
							(end -0.2794 0.1778)
						)
						(arc
							(start -0.2794 -0.1778)
							(mid -0.249642 -0.249642)
							(end -0.1778 -0.2794)
						)
						(arc
							(start 0.1778 -0.2794)
							(mid 0.249642 -0.249642)
							(end 0.2794 -0.1778)
						)
						(arc
							(start 0.2794 0.1778)
							(mid 0.249642 0.249642)
							(end 0.1778 0.2794)
						)
					)
					(width 0)
					(fill yes)
				)
			)
		)
	)
	(footprint ""
		(layer "B.Cu")
		(at 168.656 -125.603 -90)
		(property "Reference" "C6M6"
			(at 0.8382 -0.84963 270)
			(unlocked yes)
			(layer "B.SilkS")
			(effects
				(font
					(size 0.7874 0.5842)
					(thickness 0.1524)
				)
				(justify left mirror)
			)
		)
		(property "Value" ""
			(at 0 0 90)
			(layer "B.Fab")
			(effects
				(font
					(size 1.27 1.27)
				)
				(justify mirror)
			)
		)
		(duplicate_pad_numbers_are_jumpers no)
		(fp_poly
			(pts
				(xy -0.3048 -0.1016) (xy -0.3048 0.9906) (xy 0.3048 0.9906) (xy 0.3048 -0.1016)
			)
			(stroke
				(width 0)
				(type default)
			)
			(fill no)
			(layer "B.CrtYd")
		)
		(fp_line
			(start -0.3048 0.9906)
			(end -0.3048 -0.1016)
			(stroke
				(width 0.1)
				(type default)
			)
			(layer "B.Fab")
		)
		(fp_line
			(start 0.3048 0.9906)
			(end -0.3048 0.9906)
			(stroke
				(width 0.1)
				(type default)
			)
			(layer "B.Fab")
		)
		(fp_line
			(start -0.3048 -0.1016)
			(end 0.3048 -0.1016)
			(stroke
				(width 0.1)
				(type default)
			)
			(layer "B.Fab")
		)
		(fp_line
			(start 0.3048 -0.1016)
			(end 0.3048 0.9906)
			(stroke
				(width 0.1)
				(type default)
			)
			(layer "B.Fab")
		)
		(pad "1" smd rect
			(at 0 0 90)
			(size 0.508 0.508)
			(layers "B.Cu" "B.Mask" "B.Paste")
			(net "JTAG_MCP_CPU1_TDI_R")
		)
		(pad "2" smd rect
			(at 0 0.889 90)
			(size 0.508 0.508)
			(layers "B.Cu" "B.Mask" "B.Paste")
			(net "GND")
		)
		(zone
			(layer "B.Cu")
			(hatch none 0.5)
			(connect_pads
				(clearance 0)
			)
			(min_thickness 0.25)
			(keepout
				(tracks not_allowed)
				(vias allowed)
				(pads allowed)
				(copperpour not_allowed)
				(footprints allowed)
			)
			(placement
				(enabled no)
				(sheetname "")
			)
			(fill
				(thermal_gap 0.5)
				(thermal_bridge_width 0.5)
				(island_removal_mode 0)
			)
			(polygon
				(pts
					(xy 168.021 -125.349) (xy 168.021 -125.857) (xy 168.402 -125.857) (xy 168.402 -125.349)
				)
			)
		)
		(zone
			(layer "B.Cu")
			(hatch none 0.5)
			(connect_pads
				(clearance 0)
			)
			(min_thickness 0.25)
			(keepout
				(tracks allowed)
				(vias not_allowed)
				(pads allowed)
				(copperpour not_allowed)
				(footprints allowed)
			)
			(placement
				(enabled no)
				(sheetname "")
			)
			(fill
				(thermal_gap 0.5)
				(thermal_bridge_width 0.5)
				(island_removal_mode 0)
			)
			(polygon
				(pts
					(xy 168.402 -125.349) (xy 168.402 -125.857) (xy 168.021 -125.857) (xy 168.021 -125.349)
				)
			)
		)
	)
	(footprint ""
		(layer "B.Cu")
		(at 197.866 -56.7182 90)
		(property "Reference" "C6R13"
			(at 0 0 90)
			(layer "B.SilkS")
			(hide yes)
			(effects
				(font
					(size 1.27 1.27)
				)
				(justify mirror)
			)
		)
		(property "Value" ""
			(at 0 0 90)
			(layer "B.Fab")
			(effects
				(font
					(size 1.27 1.27)
				)
				(justify mirror)
			)
		)
		(duplicate_pad_numbers_are_jumpers no)
		(fp_rect
			(start -0.7239 -0.2159)
			(end 0.7239 1.9939)
			(stroke
				(width 0)
				(type default)
			)
			(fill no)
			(layer "B.CrtYd")
		)
		(fp_line
			(start 0.7239 -0.2159)
			(end 0.7239 1.9939)
			(stroke
				(width 0.1)
				(type default)
			)
			(layer "B.Fab")
		)
		(fp_line
			(start -0.7239 -0.2159)
			(end 0.7239 -0.2159)
			(stroke
				(width 0.1)
				(type default)
			)
			(layer "B.Fab")
		)
		(fp_line
			(start 0.7239 1.9939)
			(end -0.7239 1.9939)
			(stroke
				(width 0.1)
				(type default)
			)
			(layer "B.Fab")
		)
		(fp_line
			(start -0.7239 1.9939)
			(end -0.7239 -0.2159)
			(stroke
				(width 0.1)
				(type default)
			)
			(layer "B.Fab")
		)
		(pad "1" smd rect
			(at 0 0 270)
			(size 1.27 1.016)
			(layers "B.Cu" "B.Mask" "B.Paste")
			(net "VR_FET_SW_P12V_STBY_PVCCIN_CPU0")
		)
		(pad "2" smd rect
			(at 0 1.778 270)
			(size 1.27 1.016)
			(layers "B.Cu" "B.Mask" "B.Paste")
			(net "GND")
		)
		(zone
			(layer "B.Cu")
			(hatch none 0.5)
			(connect_pads
				(clearance 0)
			)
			(min_thickness 0.25)
			(keepout
				(tracks not_allowed)
				(vias allowed)
				(pads allowed)
				(copperpour not_allowed)
				(footprints allowed)
			)
			(placement
				(enabled no)
				(sheetname "")
			)
			(fill
				(thermal_gap 0.5)
				(thermal_bridge_width 0.5)
				(island_removal_mode 0)
			)
			(polygon
				(pts
					(xy 198.374 -56.0832) (xy 199.136 -56.0832) (xy 199.136 -57.3532) (xy 198.374 -57.3532)
				)
			)
		)
	)
	(footprint ""
		(layer "B.Cu")
		(at 367.9444 -5.3467 180)
		(property "Reference" "R7G29"
			(at 0 0 0)
			(layer "B.SilkS")
			(hide yes)
			(effects
				(font
					(size 1.27 1.27)
				)
				(justify mirror)
			)
		)
		(property "Value" ""
			(at 0 0 0)
			(layer "B.Fab")
			(effects
				(font
					(size 1.27 1.27)
				)
				(justify mirror)
			)
		)
		(duplicate_pad_numbers_are_jumpers no)
		(fp_poly
			(pts
				(xy 0.2794 -0.1016) (xy -0.2794 -0.1016) (xy -0.2794 0.9906) (xy 0.2794 0.9906)
			)
			(stroke
				(width 0)
				(type default)
			)
			(fill no)
			(layer "B.CrtYd")
		)
		(fp_line
			(start 0.2794 0.9906)
			(end -0.2794 0.9906)
			(stroke
				(width 0.1)
				(type default)
			)
			(layer "B.Fab")
		)
		(fp_line
			(start 0.2794 -0.1016)
			(end 0.2794 0.9906)
			(stroke
				(width 0.1)
				(type default)
			)
			(layer "B.Fab")
		)
		(fp_line
			(start -0.2794 0.9906)
			(end -0.2794 -0.1016)
			(stroke
				(width 0.1)
				(type default)
			)
			(layer "B.Fab")
		)
		(fp_line
			(start -0.2794 -0.1016)
			(end 0.2794 -0.1016)
			(stroke
				(width 0.1)
				(type default)
			)
			(layer "B.Fab")
		)
		(pad "1" smd rect
			(at 0 0)
			(size 0.508 0.508)
			(layers "B.Cu" "B.Mask" "B.Paste")
			(net "PD_PASSWORD_CLEAR")
		)
		(pad "2" smd rect
			(at 0 0.889)
			(size 0.508 0.508)
			(layers "B.Cu" "B.Mask" "B.Paste")
			(net "GND")
		)
		(zone
			(layer "B.Cu")
			(hatch none 0.5)
			(connect_pads
				(clearance 0)
			)
			(min_thickness 0.25)
			(keepout
				(tracks not_allowed)
				(vias allowed)
				(pads allowed)
				(copperpour not_allowed)
				(footprints allowed)
			)
			(placement
				(enabled no)
				(sheetname "")
			)
			(fill
				(thermal_gap 0.5)
				(thermal_bridge_width 0.5)
				(island_removal_mode 0)
			)
			(polygon
				(pts
					(xy 367.6904 -5.9817) (xy 368.1984 -5.9817) (xy 368.1984 -5.6007) (xy 367.6904 -5.6007)
				)
			)
		)
		(zone
			(layer "B.Cu")
			(hatch none 0.5)
			(connect_pads
				(clearance 0)
			)
			(min_thickness 0.25)
			(keepout
				(tracks allowed)
				(vias not_allowed)
				(pads allowed)
				(copperpour not_allowed)
				(footprints allowed)
			)
			(placement
				(enabled no)
				(sheetname "")
			)
			(fill
				(thermal_gap 0.5)
				(thermal_bridge_width 0.5)
				(island_removal_mode 0)
			)
			(polygon
				(pts
					(xy 367.6904 -5.6007) (xy 368.1984 -5.6007) (xy 368.1984 -5.9817) (xy 367.6904 -5.9817)
				)
			)
		)
	)
	(footprint ""
		(layer "B.Cu")
		(at 462.8896 -7.1628)
		(property "Reference" "R2U37"
			(at 0 0 0)
			(layer "B.SilkS")
			(hide yes)
			(effects
				(font
					(size 1.27 1.27)
				)
				(justify mirror)
			)
		)
		(property "Value" ""
			(at 0 0 0)
			(layer "B.Fab")
			(effects
				(font
					(size 1.27 1.27)
				)
				(justify mirror)
			)
		)
		(duplicate_pad_numbers_are_jumpers no)
		(fp_poly
			(pts
				(xy 0.2794 -0.1016) (xy -0.2794 -0.1016) (xy -0.2794 0.9906) (xy 0.2794 0.9906)
			)
			(stroke
				(width 0)
				(type default)
			)
			(fill no)
			(layer "B.CrtYd")
		)
		(fp_line
			(start -0.2794 -0.1016)
			(end 0.2794 -0.1016)
			(stroke
				(width 0.1)
				(type default)
			)
			(layer "B.Fab")
		)
		(fp_line
			(start -0.2794 0.9906)
			(end -0.2794 -0.1016)
			(stroke
				(width 0.1)
				(type default)
			)
			(layer "B.Fab")
		)
		(fp_line
			(start 0.2794 -0.1016)
			(end 0.2794 0.9906)
			(stroke
				(width 0.1)
				(type default)
			)
			(layer "B.Fab")
		)
		(fp_line
			(start 0.2794 0.9906)
			(end -0.2794 0.9906)
			(stroke
				(width 0.1)
				(type default)
			)
			(layer "B.Fab")
		)
		(pad "1" smd rect
			(at 0 0 180)
			(size 0.508 0.508)
			(layers "B.Cu" "B.Mask" "B.Paste")
			(net "RST_PCIE_RISER1_PERST_N")
		)
		(pad "2" smd rect
			(at 0 0.889 180)
			(size 0.508 0.508)
			(layers "B.Cu" "B.Mask" "B.Paste")
			(net "RST_PCIE_RISER1_PERST_R_N")
		)
		(zone
			(layer "B.Cu")
			(hatch none 0.5)
			(connect_pads
				(clearance 0)
			)
			(min_thickness 0.25)
			(keepout
				(tracks allowed)
				(vias not_allowed)
				(pads allowed)
				(copperpour not_allowed)
				(footprints allowed)
			)
			(placement
				(enabled no)
				(sheetname "")
			)
			(fill
				(thermal_gap 0.5)
				(thermal_bridge_width 0.5)
				(island_removal_mode 0)
			)
			(polygon
				(pts
					(xy 463.1436 -6.9088) (xy 462.6356 -6.9088) (xy 462.6356 -6.5278) (xy 463.1436 -6.5278)
				)
			)
		)
		(zone
			(layer "B.Cu")
			(hatch none 0.5)
			(connect_pads
				(clearance 0)
			)
			(min_thickness 0.25)
			(keepout
				(tracks not_allowed)
				(vias allowed)
				(pads allowed)
				(copperpour not_allowed)
				(footprints allowed)
			)
			(placement
				(enabled no)
				(sheetname "")
			)
			(fill
				(thermal_gap 0.5)
				(thermal_bridge_width 0.5)
				(island_removal_mode 0)
			)
			(polygon
				(pts
					(xy 463.1436 -6.5278) (xy 462.6356 -6.5278) (xy 462.6356 -6.9088) (xy 463.1436 -6.9088)
				)
			)
		)
	)
)
